# T6G (Grand Teton) — schematic netlist excerpt (pin names and nets, part order shuffled) for the footprints in the layout excerpt that follows; sources: Cadence DE-HDL packaged netlist, KiCad conversion of 04192023_DAF0TMB3IC0_F0TG_MB_C_brd_V02_OCP.brd

Q8001  MOSFET_NCH_DUAL  PJT138K IC  pkg SOT363XD  page 256
  S1  = GND
  G1  = P12V_SCM_FAULT_R_N
  D2  = LED_P12V_SCM_FAULT_D2
  S2  = GND
  G2  = LED_P12V_SCM_FAULT_D1
  D1  = LED_P12V_SCM_FAULT_D1

PR297  Q_RES  49.9 1% CHIP  pkg 0402LF  page 193 : A = VSENSE_VSS_SENSE_A_P0 ; B = GND

(kicad_pcb
	(version 20260206)
	(generator "pcbnew")
	(generator_version "10.0")
	(general
		(thickness 1.6)
		(legacy_teardrops no)
	)
	(paper "A4")
	(title_block
		(title "04192023_DAF0TMB3IC0_F0TG_MB_C_brd_V02_OCP.brd")
		(comment 1 "Grand Teton / footprints 4113-4114 of 8354")
	)
	(layers
		(0 "F.Cu" signal "TOP")
		(4 "In1.Cu" signal "GND")
		(6 "In2.Cu" signal "IN1")
		(8 "In3.Cu" signal "GND1")
		(10 "In4.Cu" signal "IN2")
		(12 "In5.Cu" signal "GND2")
		(14 "In6.Cu" signal "IN3")
		(16 "In7.Cu" signal "GND3")
		(18 "In8.Cu" signal "VCC")
		(20 "In9.Cu" signal "VCC1")
		(22 "In10.Cu" signal "GND4")
		(24 "In11.Cu" signal "IN4")
		(26 "In12.Cu" signal "GND5")
		(28 "In13.Cu" signal "IN5")
		(30 "In14.Cu" signal "GND6")
		(32 "In15.Cu" signal "IN6")
		(34 "In16.Cu" signal "GND7")
		(2 "B.Cu" signal "BOTTOM")
		(9 "F.Adhes" user "F.Adhesive")
		(11 "B.Adhes" user "B.Adhesive")
		(13 "F.Paste" user "Package Geometry/Pastemask Top")
		(15 "B.Paste" user "Package Geometry/Pastemask Bottom")
		(5 "F.SilkS" user "Ref Des/Silkscreen Top")
		(7 "B.SilkS" user "Ref Des/Silkscreen Bottom")
		(1 "F.Mask" user "Board Geometry/Soldermask Top")
		(3 "B.Mask" user "Board Geometry/Soldermask Bottom")
		(17 "Dwgs.User" user "User.Drawings")
		(19 "Cmts.User" user "User.Comments")
		(21 "Eco1.User" user "User.Eco1")
		(23 "Eco2.User" user "User.Eco2")
		(25 "Edge.Cuts" user "Board Geometry/Outline")
		(27 "Margin" user)
		(31 "F.CrtYd" user "Package Geometry/Place Bound Top")
		(29 "B.CrtYd" user "Package Geometry/Place Bound Bottom")
		(35 "F.Fab" user "Ref Des/Assembly Top")
		(33 "B.Fab" user "Ref Des/Assembly Bottom")
	)
	(footprint ""
		(layer "F.Cu")
		(at 421.169592 -175.851312 180)
		(property "Reference" "PR297"
			(at 0 0 180)
			(layer "F.SilkS")
			(hide yes)
			(effects
				(font
					(size 1.27 1.27)
				)
			)
		)
		(property "Value" ""
			(at 0 0 180)
			(layer "F.Fab")
			(effects
				(font
					(size 1.27 1.27)
				)
			)
		)
		(duplicate_pad_numbers_are_jumpers no)
		(fp_line
			(start 0.7874 0.4064)
			(end -0.7874 0.4064)
			(stroke
				(width 0.1524)
				(type default)
			)
			(layer "F.SilkS")
		)
		(fp_line
			(start 0.7874 -0.4064)
			(end 0.7874 0.4064)
			(stroke
				(width 0.1524)
				(type default)
			)
			(layer "F.SilkS")
		)
		(fp_line
			(start -0.7874 0.4064)
			(end -0.7874 -0.4064)
			(stroke
				(width 0.1524)
				(type default)
			)
			(layer "F.SilkS")
		)
		(fp_line
			(start -0.7874 -0.4064)
			(end 0.7874 -0.4064)
			(stroke
				(width 0.1524)
				(type default)
			)
			(layer "F.SilkS")
		)
		(fp_line
			(start 0.67945 0.3048)
			(end 0.120396 0.3048)
			(stroke
				(width 0.1)
				(type default)
			)
			(layer "F.Fab")
		)
		(fp_line
			(start 0.67945 -0.3048)
			(end 0.67945 0.3048)
			(stroke
				(width 0.1)
				(type default)
			)
			(layer "F.Fab")
		)
		(fp_line
			(start 0.12065 -0.2794)
			(end 0.12065 -0.3048)
			(stroke
				(width 0.1)
				(type default)
			)
			(layer "F.Fab")
		)
		(fp_line
			(start 0.12065 -0.3048)
			(end 0.67945 -0.3048)
			(stroke
				(width 0.1)
				(type default)
			)
			(layer "F.Fab")
		)
		(fp_line
			(start 0.120396 0.3048)
			(end 0.120396 0.2794)
			(stroke
				(width 0.1)
				(type default)
			)
			(layer "F.Fab")
		)
		(fp_line
			(start 0.120396 0.2794)
			(end -0.12065 0.2794)
			(stroke
				(width 0.1)
				(type default)
			)
			(layer "F.Fab")
		)
		(fp_line
			(start -0.12065 0.3048)
			(end -0.67945 0.3048)
			(stroke
				(width 0.1)
				(type default)
			)
			(layer "F.Fab")
		)
		(fp_line
			(start -0.12065 0.2794)
			(end -0.12065 0.3048)
			(stroke
				(width 0.1)
				(type default)
			)
			(layer "F.Fab")
		)
		(fp_line
			(start -0.12065 -0.2794)
			(end 0.12065 -0.2794)
			(stroke
				(width 0.1)
				(type default)
			)
			(layer "F.Fab")
		)
		(fp_line
			(start -0.12065 -0.305054)
			(end -0.12065 -0.2794)
			(stroke
				(width 0.1)
				(type default)
			)
			(layer "F.Fab")
		)
		(fp_line
			(start -0.67945 0.3048)
			(end -0.67945 -0.305054)
			(stroke
				(width 0.1)
				(type default)
			)
			(layer "F.Fab")
		)
		(fp_line
			(start -0.67945 -0.305054)
			(end -0.12065 -0.305054)
			(stroke
				(width 0.1)
				(type default)
			)
			(layer "F.Fab")
		)
		(pad "1" smd circle
			(at -0.40005 0 180)
			(size 0 0)
			(layers "F.Cu" "F.Mask" "F.Paste")
			(net "VSENSE_VSS_SENSE_A_P0")
		)
		(pad "2" smd circle
			(at 0.40005 0 180)
			(size 0 0)
			(layers "F.Cu" "F.Mask" "F.Paste")
			(net "GND")
		)
	)
	(footprint ""
		(layer "F.Cu")
		(at 190.754 -54.991 90)
		(property "Reference" "Q8001"
			(at -1.869186 3.81254 90)
			(unlocked yes)
			(layer "F.SilkS")
			(effects
				(font
					(size 0.7874 0.5842)
					(thickness 0.1524)
				)
				(justify left)
			)
		)
		(property "Value" ""
			(at 0 0 90)
			(layer "F.Fab")
			(effects
				(font
					(size 1.27 1.27)
				)
			)
		)
		(duplicate_pad_numbers_are_jumpers no)
		(fp_line
			(start 1.332738 -1.100074)
			(end 1.332738 1.100074)
			(stroke
				(width 0.1524)
				(type default)
			)
			(layer "F.SilkS")
		)
		(fp_line
			(start 0.4826 -1.100074)
			(end 1.332738 -1.100074)
			(stroke
				(width 0.1524)
				(type default)
			)
			(layer "F.SilkS")
		)
		(fp_line
			(start -0.4826 -1.100074)
			(end 0 -0.541274)
			(stroke
				(width 0.1524)
				(type default)
			)
			(layer "F.SilkS")
		)
		(fp_line
			(start -1.332738 -1.100074)
			(end -0.4826 -1.100074)
			(stroke
				(width 0.1524)
				(type default)
			)
			(layer "F.SilkS")
		)
		(fp_line
			(start 0 -0.541274)
			(end 0.4826 -1.100074)
			(stroke
				(width 0.1524)
				(type default)
			)
			(layer "F.SilkS")
		)
		(fp_line
			(start 1.332738 1.100074)
			(end -1.332738 1.100074)
			(stroke
				(width 0.1524)
				(type default)
			)
			(layer "F.SilkS")
		)
		(fp_line
			(start -1.332738 1.100074)
			(end -1.332738 -1.100074)
			(stroke
				(width 0.1524)
				(type default)
			)
			(layer "F.SilkS")
		)
		(fp_poly
			(pts
				(xy -2.323338 0.090932) (xy -2.490978 -0.590804) (xy -1.725422 -0.417576)
			)
			(stroke
				(width 0)
				(type default)
			)
			(fill yes)
			(layer "F.SilkS")
		)
		(fp_line
			(start 0.674878 -1.100074)
			(end 0.674878 1.100074)
			(stroke
				(width 0.1)
				(type default)
			)
			(layer "F.Fab")
		)
		(fp_line
			(start -0.674878 -1.100074)
			(end 0.674878 -1.100074)
			(stroke
				(width 0.1)
				(type default)
			)
			(layer "F.Fab")
		)
		(fp_line
			(start 0.674878 1.100074)
			(end -0.674878 1.100074)
			(stroke
				(width 0.1)
				(type default)
			)
			(layer "F.Fab")
		)
		(fp_line
			(start -0.674878 1.100074)
			(end -0.674878 -1.100074)
			(stroke
				(width 0.1)
				(type default)
			)
			(layer "F.Fab")
		)
		(fp_poly
			(pts
				(xy -2.2352 -0.298958) (xy -2.2352 -1.001014) (xy -1.533144 -0.649986)
			)
			(stroke
				(width 0)
				(type default)
			)
			(fill yes)
			(layer "F.Fab")
		)
		(pad "1" smd rect
			(at -0.94996 -0.649986 180)
			(size 0.4318 0.508)
			(layers "F.Cu" "F.Mask" "F.Paste")
			(net "GND")
		)
		(pad "2" smd rect
			(at -0.94996 0 180)
			(size 0.4318 0.508)
			(layers "F.Cu" "F.Mask" "F.Paste")
			(net "P12V_SCM_FAULT_R_N")
		)
		(pad "3" smd rect
			(at -0.94996 0.649986 180)
			(size 0.4318 0.508)
			(layers "F.Cu" "F.Mask" "F.Paste")
			(net "LED_P12V_SCM_FAULT_D2")
		)
		(pad "4" smd rect
			(at 0.94996 0.649986 180)
			(size 0.4318 0.508)
			(layers "F.Cu" "F.Mask" "F.Paste")
			(net "GND")
		)
		(pad "5" smd rect
			(at 0.94996 0 180)
			(size 0.4318 0.508)
			(layers "F.Cu" "F.Mask" "F.Paste")
			(net "LED_P12V_SCM_FAULT_D1")
		)
		(pad "6" smd rect
			(at 0.94996 -0.649986 180)
			(size 0.4318 0.508)
			(layers "F.Cu" "F.Mask" "F.Paste")
			(net "LED_P12V_SCM_FAULT_D1")
		)
	)
)
